<schema xmlns="http://www.cadence.com/spb/csschema"
	xmlns:xsi="http://www.w3.org/2001/XMLSchema-instance"
	xsi:schemaLocation="http://www.cadence.com/spb/csschema CSSchema002.xsd">
  <header>
    <schemaVersion>16.5</schemaVersion>
    <creatorTool>conceptHDL</creatorTool>
    <modifierTool>conceptHDL</modifierTool>
    <modificationTime>2011-10-25T14:26:29</modificationTime>
    <savedLibrary>mstr_symbols</savedLibrary>
  </header>
  <designs>
    <design schemaType="nameBased" name="p3v3_stby" view="sch_1">
      <lastids>
        <netid>4</netid>
      </lastids>
      <cells>
      </cells>
      <nets>
        <net>
          <id>N1</id>
          <name>g</name>
          <scope>interface</scope>
          <direction>inout</direction>
        </net>
        <net>
          <id>N2</id>
          <name>page1_g</name>
        </net>
        <net>
          <id>N4</id>
          <name>page1_p3v3_stby</name>
        </net>
        <net>
          <id>N3</id>
          <name>p3v3_stby</name>
          <scope>global</scope>
        </net>
      </nets>
      <aliases>
        <alias net1="N2" lsb1="-1" msb1="-1" net2="N1" lsb2="-1" msb2="-1" />
        <alias net1="N4" lsb1="-1" msb1="-1" net2="N2" lsb2="-1" msb2="-1" />
        <alias net1="N4" lsb1="-1" msb1="-1" net2="N3" lsb2="-1" msb2="-1" />
      </aliases>
      <differentialnets>
      </differentialnets>
      <differentialbusnets>
      </differentialbusnets>
      <netgroups>
      </netgroups>
      <netinterfaces>
      </netinterfaces>
      <instances>
      </instances>
      <templateresolutions>
      </templateresolutions>
      <templateinstances>
      </templateinstances>
      <extensions>
        <extension name="schematic_extension">
        <schematicExtension>
        <errorStatus>true</errorStatus>
        <netScopes>
          <netScope ref="g">
            <pageScope number="1">
              <scope>interface</scope>
              <direction>unknown</direction>
            </pageScope>
          </netScope>
          <netScope ref="p3v3_stby">
            <pageScope number="1">
              <scope>global</scope>
            </pageScope>
          </netScope>
        </netScopes>
        <pages>
          <page number="1">
            <physicalPageNumber>1</physicalPageNumber>
            <errorStatus>false</errorStatus>
            <nets>
              <net ref="g"></net>
              <net ref="p3v3_stby"></net>
            </nets>
            <instances>
            </instances>
          </page>
        </pages>
      </schematicExtension>
        </extension>
      </extensions>
    </design>
  </designs>
</schema>
